FILE_TYPE = CONNECTIVITY;
{Allegro Design Entry HDL 16.6-p007 (v16-6-112F) 10/10/2012}
"PAGE_NUMBER" = 139;
0"NC";
1"GND\g";
2"GND\g";
3"GND\g";
4"GND\g";
5"GND\g";
6"P1V5_LAN\g";
7"P0V9_LAN\g";
8"GND\g";
9"GND\g";
10"P3V3_STBY\g";
11"P3V3_STBY\g";
12"P3V3_STBY\g";
13"P3V3_STBY\g";
14"P3V3_STBY\g";
15"P3V3_STBY\g";
16"P3V3_STBY\g";
17"GND\g";
18"GND\g";
19"GND\g";
20"GND\g";
21"GND\g";
22"P0V9_LAN\g";
23"P1V5_LAN\g"VOLTAGE"+1.5V";
24"GND\g";
25"TP_SPRV_SDP3";
26"RMII_SPRNGVLLE_BMC_PCH_RXD0";
27"SPI_NIC_CS_R_N";
28"SPI_NIC_SCLK";
29"PE_PCH_SPRV_RX_DN";
30"PE_PCH_SPRV_RX_C_DP";
31"SPI_NIC_CS_N";
32"RMII_BMC_PCH_SPRNGVLLE_TXEN";
33"PE_PCH_SPRV_RX_C_DN";
34"RMII_BMC_PCH_SPRNGVLLE_CRSDV";
35"A_CBOT";
36"TP_SPRV_SDP2";
37"FM_1GB_LOM_DISABLE_N";
38"TP_SPRV_SDP0";
39"XTAL_25MHZ_IN";
40"PU_DEV_OFF_N";
41"IRQ_LOM_ALERT_N";
42"PD_SPRV_RSET";
43"SPI_NIC_MOSI";
44"RMII_PCH_SPRNGVLLE_ARB_IN_R";
45"RMII_SPRNGVLLE_BMC_PCH_RXD1_R";
46"SPI_NIC_SCLK_R";
47"RMII_PCH_SPRNGVLLE_ARB_IN";
48"RST_PLTRST_SPRV_R_N";
49"XTAL_25MHZ_IN_R";
50"PE_PCH_SPRV_TX_DN";
51"RST_PLTRST_N";
52"PE_PCH_SPRV_TX_DP";
53"CLK_50M_CKMNG_SPRVLLE";
54"XTAL_25MHZ_OUT";
55"PE_PCH_SPRV_RX_DP";
56"SPI_NIC_MOSI_R";
57"RMII_BMC_PCH_SPRNGVLLE_TXEN";
58"RMII_BMC_PCH_SPRNGVLLE_CRSDV_R";
59"CLK_50M_CKMNG_SPRVLLE";
60"RMII_PCH_SPRNGVLLE_ARB_OUT";
61"LED_LAN_2_N";
62"LED_LAN_0_N";
63"A_CTOP";
64"NIC_SER_P_MDI_3_DP";
65"NIC_SER_N_MDI_3_DN";
66"NIC_SET_P_MDI_2_DP";
67"NIC_SET_N_MDI_2_DN";
68"NIC_MDI_SPRV_RJ45_1_DP";
69"NIC_MDI_SPRV_RJ45_1_DN";
70"NIC_MDI_SPRV_RJ45_0_DN";
71"NIC_MDI_SPRV_RJ45_0_DP";
72"PE_PCH_SPRV_TX_C_DN";
73"RST_PLTRST_SPRV_R_N";
74"PE_PCH_SPRV_TX_C_DP";
75"PD_SPRV_RSET";
76"PU_SPRV_LAN_PWR_GOOD";
77"SPI_NIC_MISO";
78"RMII_BMC_PCH_SPRNGVLLE_TXD1";
79"RMII_BMC_PCH_SPRNGVLLE_TXD0";
80"P0V9_LAN_I210"VOLTAGE"0.9";
81"P1V5_LAN_I210"VOLTAGE"1.5";
82"RMII_SPRNGVLLE_BMC_PCH_RXD0_R";
83"RMII_SPRNGVLLE_BMC_PCH_RXD1";
84"SMB_SPRINGVILLE_STBY_LVC3_SCL";
85"RMII_BMC_PCH_SPRNGVLLE_CRSDV";
86"PU_JTAG_SPRV_TDI";
87"XTAL_25MHZ_OUT_R";
88"CLK_100M_SPRV_DN";
89"CLK_100M_SPRV_DP";
90"FM_PE_SPRV_WAKE_N";
91"LED_LAN_1_N";
92"SMB_SPRINGVILLE_STBY_LVC3_SDA";
93"IRQ_LOM_ALERT_N";
94"PU_JTAG_SPRV_TDO";
95"P3V3_STBY_P1V5_LAN_I210"VOLTAGE"3.3";
96"XTAL_25MHZ_IN_R";
97"XTAL_25MHZ_OUT";
98"PU_SPRV_LAN_PWR_GOOD";
99"PU_JTAG_SPRV_TCK";
100"PU_JTAG_SPRV_TMS";
%"CRYSTAL"
"1","(-7525,1475)","0","mstr_discrete","I109";
;
CDS_SEC"1"
GROUP"NI_I210&RJ45"
VALUE"25.000MHZ"
PART_NUMBER"D71700-057"
LOCATION"Y9E1"
MATERIAL"IC"
CDS_LIB"mstr_discrete"
PACK_TYPE"2013"
ROOM"NIC_SPRV"
CDS_LOCATION"Y9E1"
SEC"1"
SEC_TYPE"2013"
BOM_COST"NT_GBE_BASE";
"B"
$PN"3"87;
"A"
$PN"1"39;
%"RES"
"1","(-6800,1675)","0","mstr_discrete","I110";
;
CDS_SEC"1"
WATTAGE"1/16W"
PACK_TYPE"0402"
TOLERANCE"5%"
LOCATION"R9E20"
MATERIAL"CHIP"
PART_NUMBER"G21497-005"
VALUE"0.0"
GROUP"NI_I210&RJ45"
CDS_LOCATION"R9E20"
ROOM"NIC_SPRV"
BOM_COST"NT_GBE_BASE"
SEC_TYPE"0402"
SEC"1"
CDS_LIB"mstr_discrete";
"B"
$PN"2"49;
"A"
$PN"1"39;
%"GND"
"1","(-7325,825)","0","mstr_symbols","I113";
;
VOLTAGE"0.0V"
SIZE"1B"
CDS_LIB"mstr_symbols"
BODY_TYPE"PLUMBING"
HDL_POWER"GND";
"A\NAC"1;
%"GND"
"1","(-7750,825)","0","mstr_symbols","I114";
;
CDS_LIB"mstr_symbols"
VOLTAGE"0.0V"
SIZE"1B"
BODY_TYPE"PLUMBING"
HDL_POWER"GND";
"A\NAC"2;
%"RES"
"1","(-2400,2375)","0","mstr_discrete","I128";
;
CDS_SEC"1"
PACK_TYPE"0402"
VALUE"33.2"
MATERIAL"CHIP"
LOCATION"R9E9"
TOLERANCE"1%"
PART_NUMBER"G21796-074"
GROUP"NI_I210&RJ45"
WATTAGE"1/16W"
SEC_TYPE"0402"
SEC"1"
BOM_COST"NT_GBE_BASE"
CDS_LOCATION"R9E9"
CDS_LIB"mstr_discrete"
ROOM"NIC_SPRV";
"B"
$PN"2"43;
"A"
$PN"1"56;
%"RES"
"1","(-1850,2325)","0","mstr_discrete","I129";
;
CDS_SEC"1"
WATTAGE"1/16W"
MATERIAL"CHIP"
SEC_TYPE"0402"
TOLERANCE"1%"
VALUE"33.2"
GROUP"NI_I210&RJ45"
LOCATION"R9E5"
PART_NUMBER"G21796-074"
CDS_LOCATION"R9E5"
PACK_TYPE"0402"
BOM_COST"NT_GBE_BASE"
SEC"1"
CDS_LIB"mstr_discrete"
ROOM"NIC_SPRV";
"B"
$PN"2"31;
"A"
$PN"1"27;
%"RES"
"1","(-2400,2275)","0","mstr_discrete","I130";
;
CDS_SEC"1"
PACK_TYPE"0402"
WATTAGE"1/16W"
MATERIAL"CHIP"
TOLERANCE"1%"
VALUE"33.2"
LOCATION"R9E8"
GROUP"NI_I210&RJ45"
PART_NUMBER"G21796-074"
CDS_LOCATION"R9E8"
BOM_COST"NT_GBE_BASE"
ROOM"NIC_SPRV"
SEC_TYPE"0402"
SEC"1"
CDS_LIB"mstr_discrete";
"B"
$PN"2"28;
"A"
$PN"1"46;
%"CAP"
"1","(-5975,4275)","0","mstr_discrete","I134";
;
CDS_SEC"1"
GROUP"NI_I210&RJ45"
MATERIAL"X6S"
PACK_TYPE"0603"
PART_NUMBER"E15431-002"
TOLERANCE"20%"
VOLTAGE"6.3V"
VALUE"10UF"
LOCATION"C1T4"
CDS_LIB"mstr_discrete"
BOM_COST"NT_GBE_BASE"
ROOM"NIC_SPRV"
SEC_TYPE"0603"
SEC"1"
CDS_LOCATION"C1T4";
"A"
$PN"1"22;
"B"
$PN"2"5;
%"CAP"
"1","(-6375,3975)","0","mstr_discrete","I135";
;
CDS_SEC"1"
GROUP"NI_I210&RJ45"
LOCATION"C1R30"
VALUE"10UF"
PACK_TYPE"0603"
MATERIAL"X6S"
TOLERANCE"20%"
VOLTAGE"6.3V"
PART_NUMBER"E15431-002"
ROOM"NIC_SPRV"
SEC"1"
BOM_COST"NT_GBE_BASE"
SEC_TYPE"0603"
CDS_LOCATION"C1R30"
CDS_LIB"mstr_discrete";
"A"
$PN"1"23;
"B"
$PN"2"4;
%"CAP"
"1","(-6950,3750)","0","mstr_discrete","I136";
;
CDS_SEC"1"
GROUP"NI_I210&RJ45"
PART_NUMBER"E15431-002"
VOLTAGE"6.3V"
VALUE"10UF"
MATERIAL"X6S"
LOCATION"C1R22"
TOLERANCE"20%"
PACK_TYPE"0603"
CDS_LIB"mstr_discrete"
CDS_LOCATION"C1R22"
ROOM"NIC_SPRV"
SEC"1"
BOM_COST"NT_GBE_BASE"
SEC_TYPE"0603";
"A"
$PN"1"12;
"B"
$PN"2"3;
%"GND"
"1","(-6950,3500)","0","mstr_symbols","I137";
;
CDS_LIB"mstr_symbols"
VOLTAGE"0.0V"
SIZE"1B"
BODY_TYPE"PLUMBING"
HDL_POWER"GND";
"A\NAC"3;
%"GND"
"1","(-6375,3750)","0","mstr_symbols","I138";
;
HDL_POWER"GND"
BODY_TYPE"PLUMBING"
VOLTAGE"0.0V"
CDS_LIB"mstr_symbols"
SIZE"1B";
"A\NAC"4;
%"GND"
"1","(-5975,4050)","0","mstr_symbols","I139";
;
VOLTAGE"0.0V"
CDS_LIB"mstr_symbols"
SIZE"1B"
BODY_TYPE"PLUMBING"
HDL_POWER"GND";
"A\NAC"5;
%"CAP"
"1","(-5450,850)","0","mstr_discrete","I142";
;
PACK_TYPE"0603"
VALUE"10UF"
LOCATION"C1R13"
PART_NUMBER"E15431-002"
MATERIAL"X6S"
TOLERANCE"20%"
VOLTAGE"6.3V"
GROUP"NI_I210&RJ45"
CDS_LIB"mstr_discrete"
CDS_LOCATION"C1R13"
BOM_COST"NT_GBE_BASE"
CDS_SEC"1"
ROOM"NIC_SPRV"
$SEC"1";
"A"
$PN"1"14;
"B"
$PN"2"20;
%"CAP_A"
"1","(-5200,850)","0","dev_discrete","I143";
;
TOLERANCE"10%"
LOCATION"C1R20"
MATERIAL"X7R"
VOLTAGE"16V"
VALUE"0.1UF"
PACK_TYPE"0402V"
PART_NUMBER"A36096-030"
GROUP"NI_I210&RJ45"
CDS_LOCATION"C1R20"
CDS_LIB"dev_discrete"
$SEC"1"
CDS_SEC"1"
BOM_COST"NT_GBE_BASE"
ROOM"NIC_SPRV";
"B"
$PN"2"20;
"A"
$PN"1"14;
%"CAP_A"
"1","(-4950,850)","0","dev_discrete","I144";
;
PART_NUMBER"A36096-030"
PACK_TYPE"0402V"
LOCATION"C1T3"
MATERIAL"X7R"
TOLERANCE"10%"
VOLTAGE"16V"
VALUE"0.1UF"
GROUP"NI_I210&RJ45"
CDS_LOCATION"C1T3"
CDS_LIB"dev_discrete"
ROOM"NIC_SPRV"
BOM_COST"NT_GBE_BASE"
$SEC"1"
CDS_SEC"1";
"B"
$PN"2"20;
"A"
$PN"1"14;
%"CAP_A"
"1","(-4700,850)","0","dev_discrete","I145";
;
LOCATION"C1R14"
PART_NUMBER"A36096-030"
TOLERANCE"10%"
VOLTAGE"16V"
VALUE"0.1UF"
MATERIAL"X7R"
PACK_TYPE"0402V"
GROUP"NI_I210&RJ45"
CDS_LOCATION"C1R14"
CDS_LIB"dev_discrete"
$SEC"1"
CDS_SEC"1"
BOM_COST"NT_GBE_BASE"
ROOM"NIC_SPRV";
"B"
$PN"2"20;
"A"
$PN"1"14;
%"CAP_A"
"1","(-4450,850)","0","dev_discrete","I146";
;
PACK_TYPE"0402V"
VOLTAGE"16V"
TOLERANCE"10%"
MATERIAL"X7R"
VALUE"0.1UF"
LOCATION"C1R21"
PART_NUMBER"A36096-030"
GROUP"NI_I210&RJ45"
CDS_LOCATION"C1R21"
CDS_LIB"dev_discrete"
$SEC"1"
CDS_SEC"1"
BOM_COST"NT_GBE_BASE"
ROOM"NIC_SPRV";
"B"
$PN"2"20;
"A"
$PN"1"14;
%"CAP_A"
"1","(-2325,875)","0","dev_discrete","I149";
;
TOLERANCE"10%"
LOCATION"C1R26"
PACK_TYPE"0402V"
PART_NUMBER"A36096-030"
MATERIAL"X7R"
VALUE"0.1UF"
VOLTAGE"16V"
GROUP"NI_I210&RJ45"
CDS_LIB"dev_discrete"
CDS_LOCATION"C1R26"
$SEC"1"
CDS_SEC"1"
BOM_COST"NT_GBE_BASE"
ROOM"NIC_SPRV";
"B"
$PN"2"21;
"A"
$PN"1"6;
%"CAP_A"
"1","(-2575,875)","0","dev_discrete","I150";
;
MATERIAL"X7R"
LOCATION"C1R29"
PACK_TYPE"0402V"
PART_NUMBER"A36096-030"
TOLERANCE"10%"
VOLTAGE"16V"
VALUE"0.1UF"
GROUP"NI_I210&RJ45"
CDS_LIB"dev_discrete"
CDS_LOCATION"C1R29"
$SEC"1"
CDS_SEC"1"
BOM_COST"NT_GBE_BASE"
ROOM"NIC_SPRV";
"B"
$PN"2"21;
"A"
$PN"1"6;
%"CAP_A"
"1","(-2825,875)","0","dev_discrete","I151";
;
VOLTAGE"16V"
VALUE"0.1UF"
TOLERANCE"10%"
MATERIAL"X7R"
PART_NUMBER"A36096-030"
PACK_TYPE"0402V"
LOCATION"C1R19"
GROUP"NI_I210&RJ45"
CDS_LIB"dev_discrete"
CDS_LOCATION"C1R19"
$SEC"1"
CDS_SEC"1"
BOM_COST"NT_GBE_BASE"
ROOM"NIC_SPRV";
"B"
$PN"2"21;
"A"
$PN"1"6;
%"CAP_A"
"1","(-3075,875)","0","dev_discrete","I152";
;
CDS_LOCATION"C1R31"
LOCATION"C1R31"
VALUE"0.1UF"
VOLTAGE"16V"
TOLERANCE"10%"
PART_NUMBER"A36096-030"
MATERIAL"X7R"
PACK_TYPE"0402V"
GROUP"NI_I210&RJ45"
CDS_LIB"dev_discrete"
$SEC"1"
CDS_SEC"1"
BOM_COST"NT_GBE_BASE"
ROOM"NIC_SPRV";
"B"
$PN"2"21;
"A"
$PN"1"6;
%"CAP"
"1","(-3325,875)","0","mstr_discrete","I153";
;
VALUE"10UF"
MATERIAL"X6S"
LOCATION"C1R17"
VOLTAGE"6.3V"
PART_NUMBER"E15431-002"
PACK_TYPE"0603"
TOLERANCE"20%"
GROUP"NI_I210&RJ45"
CDS_LOCATION"C1R17"
CDS_LIB"mstr_discrete"
$SEC"1"
CDS_SEC"1"
BOM_COST"NT_GBE_BASE"
ROOM"NIC_SPRV";
"A"
$PN"1"6;
"B"
$PN"2"21;
%"P1V5_LAN"
"1","(-4150,1200)","0","mstr_symbols","I154";
;
HDL_POWER"P1V5_LAN"
BODY_TYPE"PLUMBING"
CDS_LIB"mstr_symbols"
VOLTAGE"1.5V";
"G\NAC"6;
%"CAP_A"
"1","(-350,875)","0","dev_discrete","I157";
;
GROUP"NI_I210&RJ45"
PART_NUMBER"A36096-030"
VALUE"0.1UF"
TOLERANCE"10%"
LOCATION"C1R18"
MATERIAL"X7R"
PACK_TYPE"0402V"
VOLTAGE"16V"
CDS_LIB"dev_discrete"
CDS_LOCATION"C1R18"
$SEC"1"
CDS_SEC"1"
BOM_COST"NT_GBE_BASE"
ROOM"NIC_SPRV";
"B"
$PN"2"8;
"A"
$PN"1"7;
%"CAP_A"
"1","(-600,875)","0","dev_discrete","I158";
;
LOCATION"C1T5"
VALUE"0.1UF"
VOLTAGE"16V"
TOLERANCE"10%"
PACK_TYPE"0402V"
PART_NUMBER"A36096-030"
MATERIAL"X7R"
GROUP"NI_I210&RJ45"
CDS_LOCATION"C1T5"
CDS_LIB"dev_discrete"
$SEC"1"
CDS_SEC"1"
BOM_COST"NT_GBE_BASE"
ROOM"NIC_SPRV";
"B"
$PN"2"8;
"A"
$PN"1"7;
%"CAP_A"
"1","(-850,875)","0","dev_discrete","I159";
;
GROUP"NI_I210&RJ45"
LOCATION"C1R24"
VALUE"0.1UF"
MATERIAL"X7R"
TOLERANCE"10%"
VOLTAGE"16V"
PART_NUMBER"A36096-030"
PACK_TYPE"0402V"
CDS_LOCATION"C1R24"
CDS_LIB"dev_discrete"
ROOM"NIC_SPRV"
BOM_COST"NT_GBE_BASE"
CDS_SEC"1"
$SEC"1";
"B"
$PN"2"8;
"A"
$PN"1"7;
%"CAP_A"
"1","(-1100,875)","0","dev_discrete","I160";
;
MATERIAL"X7R"
VOLTAGE"16V"
TOLERANCE"10%"
VALUE"0.1UF"
LOCATION"C1R15"
PART_NUMBER"A36096-030"
PACK_TYPE"0402V"
GROUP"NI_I210&RJ45"
CDS_LOCATION"C1R15"
CDS_LIB"dev_discrete"
ROOM"NIC_SPRV"
BOM_COST"NT_GBE_BASE"
CDS_SEC"1"
$SEC"1";
"B"
$PN"2"8;
"A"
$PN"1"7;
%"CAP"
"1","(-1350,875)","0","mstr_discrete","I161";
;
VOLTAGE"6.3V"
TOLERANCE"20%"
MATERIAL"X6S"
VALUE"10UF"
LOCATION"C1R16"
PART_NUMBER"E15431-002"
PACK_TYPE"0603"
GROUP"NI_I210&RJ45"
CDS_LOCATION"C1R16"
CDS_LIB"mstr_discrete"
BOM_COST"NT_GBE_BASE"
CDS_SEC"1"
$SEC"1"
ROOM"NIC_SPRV";
"A"
$PN"1"7;
"B"
$PN"2"8;
%"P0V9_LAN"
"1","(-1925,1150)","0","mstr_symbols","I162";
;
VOLTAGE"0.9V"
CDS_LIB"mstr_symbols"
BODY_TYPE"PLUMBING"
HDL_POWER"P0V9_LAN";
"G\NAC"7;
%"CAP_A"
"1","(-1600,875)","0","dev_discrete","I163";
;
CDS_SEC"1"
LOCATION"C9E1"
MATERIAL"EMPTY"
PART_NUMBER"E15431-004"
PACK_TYPE"0603V"
VOLTAGE"4V"
TOLERANCE"20%"
VALUE"22.0UF"
GROUP"NI_I210&RJ45"
CDS_LIB"dev_discrete"
CDS_LOCATION"C9E1"
ROOM"NIC_SPRV"
SEC_TYPE"0603V"
SEC"1"
BOM_COST"NT_GBE_BASE";
"B"
$PN"2"8;
"A"
$PN"1"7;
%"GND"
"1","(-1925,575)","0","mstr_symbols","I164";
;
VOLTAGE"0.0V"
CDS_LIB"mstr_symbols"
SIZE"1B"
BODY_TYPE"PLUMBING"
HDL_POWER"GND";
"A\NAC"8;
%"RES"
"2","(-900,3825)","0","mstr_discrete","I173";
;
PACK_TYPE"0402"
TOLERANCE"1%"
WATTAGE"1/16W"
MATERIAL"CHIP"
PART_NUMBER"G21796-027"
VALUE"3.32K"
LOCATION"R9F5"
GROUP"NI_I210&RJ45"
CDS_LIB"mstr_discrete"
ROOM"NIC_SPRV"
CDS_LOCATION"R9F5"
$SEC"1"
BOM_COST"NT_GBE_BASE"
CDS_SEC"1";
"A"
$PN"1"13;
"B"
$PN"2"76;
%"RES"
"2","(-900,3225)","0","mstr_discrete","I174";
;
CDS_SEC"1"
PART_NUMBER"G21796-013"
PACK_TYPE"0402"
GROUP"NI_I210&RJ45"
MATERIAL"CHIP"
TOLERANCE"1%"
WATTAGE"1/16W"
VALUE"4.99K"
LOCATION"R9E23"
CDS_LIB"mstr_discrete"
ROOM"NIC_SPRV"
CDS_LOCATION"R9E23"
SEC_TYPE"0402"
BOM_COST"NT_GBE_BASE"
SEC"1";
"A"
$PN"1"42;
"B"
$PN"2"9;
%"GND"
"1","(-900,2950)","0","mstr_symbols","I176";
;
SIZE"1B"
CDS_LIB"mstr_symbols"
VOLTAGE"0.0V"
BODY_TYPE"PLUMBING"
HDL_POWER"GND";
"A\NAC"9;
%"RES"
"2","(-7200,3125)","0","mstr_discrete","I177";
;
CDS_SEC"1"
GROUP"NI_I210&RJ45"
VALUE"10.0K"
LOCATION"R9E2"
MATERIAL"CHIP"
WATTAGE"1/16W"
PACK_TYPE"0402"
PART_NUMBER"G21796-016"
TOLERANCE"1%"
CDS_LIB"mstr_discrete"
CDS_LOCATION"R9E2"
ROOM"NIC_SPRV"
SEC"1"
SEC_TYPE"0402"
BOM_COST"NT_GBE_BASE";
"A"
$PN"1"10;
"B"
$PN"2"99;
%"RES"
"2","(-7475,3125)","0","mstr_discrete","I178";
;
CDS_SEC"1"
LOCATION"R9E3"
VALUE"10.0K"
WATTAGE"1/16W"
PACK_TYPE"0402"
TOLERANCE"1%"
MATERIAL"CHIP"
PART_NUMBER"G21796-016"
GROUP"NI_I210&RJ45"
CDS_LIB"mstr_discrete"
CDS_LOCATION"R9E3"
ROOM"NIC_SPRV"
SEC"1"
SEC_TYPE"0402"
BOM_COST"NT_GBE_BASE";
"A"
$PN"1"10;
"B"
$PN"2"100;
%"RES"
"2","(-7750,3125)","0","mstr_discrete","I179";
;
CDS_SEC"1"
PART_NUMBER"G21796-016"
LOCATION"R9E1"
VALUE"10.0K"
TOLERANCE"1%"
WATTAGE"1/16W"
MATERIAL"CHIP"
GROUP"NI_I210&RJ45"
PACK_TYPE"0402"
SEC_TYPE"0402"
BOM_COST"NT_GBE_BASE"
SEC"1"
ROOM"NIC_SPRV"
CDS_LOCATION"R9E1"
CDS_LIB"mstr_discrete";
"A"
$PN"1"10;
"B"
$PN"2"86;
%"P3V3_STBY"
"1","(-7750,3550)","0","mstr_symbols","I180";
;
CDS_LIB"mstr_symbols"
SIZE"1B"
VOLTAGE"3.3V"
BODY_TYPE"PLUMBING"
HDL_POWER"P3V3_STBY";
"G\NAC"10;
%"RES"
"1","(-1500,2825)","0","mstr_discrete","I181";
;
CDS_SEC"1"
WATTAGE"1/16W"
LOCATION"R9E22"
MATERIAL"CHIP"
VALUE"10.0K"
PACK_TYPE"0402"
TOLERANCE"1%"
PART_NUMBER"G21796-016"
GROUP"NI_I210&RJ45"
ROOM"NIC_SPRV"
SEC"1"
BOM_COST"NT_GBE_BASE"
SEC_TYPE"0402"
CDS_LIB"mstr_discrete"
CDS_LOCATION"R9E22";
"B"
$PN"2"11;
"A"
$PN"1"94;
%"P3V3_STBY"
"1","(-1175,3200)","0","mstr_symbols","I182";
;
CDS_LIB"mstr_symbols"
SIZE"1B"
VOLTAGE"3.3V"
BODY_TYPE"PLUMBING"
HDL_POWER"P3V3_STBY";
"G\NAC"11;
%"P3V3_STBY"
"1","(-6950,4000)","0","mstr_symbols","I186";
;
VOLTAGE"3.3V"
SIZE"1B"
CDS_LIB"mstr_symbols"
BODY_TYPE"PLUMBING"
HDL_POWER"P3V3_STBY";
"G\NAC"12;
%"P3V3_STBY"
"1","(-900,4050)","0","mstr_symbols","I188";
;
VOLTAGE"3.3V"
CDS_LIB"mstr_symbols"
SIZE"1B"
BODY_TYPE"PLUMBING"
HDL_POWER"P3V3_STBY";
"G\NAC"13;
%"P3V3_STBY"
"1","(-6200,1200)","0","mstr_symbols","I189";
;
HDL_POWER"P3V3_STBY"
BODY_TYPE"PLUMBING"
SIZE"1B"
VOLTAGE"3.3V"
CDS_LIB"mstr_symbols";
"G\NAC"14;
%"RES"
"2","(-1000,4475)","0","mstr_discrete","I193";
;
PACK_TYPE"0402"
VALUE"3.32K"
MATERIAL"CHIP"
LOCATION"R9E7"
TOLERANCE"1%"
WATTAGE"1/16W"
PART_NUMBER"G21796-027"
CDS_LIB"mstr_discrete"
CDS_LOCATION"R9E7"
CDS_SEC"1"
$SEC"1"
ROOM"NIC_SPRV"
BOM_COST"NT_GBE_BASE";
"A"
$PN"1"15;
"B"
$PN"2"41;
%"P3V3_STBY"
"1","(-1000,4700)","0","mstr_symbols","I194";
;
VOLTAGE"3.3V"
CDS_LIB"mstr_symbols"
SIZE"1B"
BODY_TYPE"PLUMBING"
HDL_POWER"P3V3_STBY";
"G\NAC"15;
%"RES"
"1","(-7075,350)","0","mstr_discrete","I195";
;
CDS_SEC"1"
TOLERANCE"5%"
WATTAGE"1/16W"
LOCATION"R1R1"
VALUE"0.0"
PART_NUMBER"G21497-005"
MATERIAL"CHIP"
PACK_TYPE"0402"
ROOM"NIC_SPRV"
BOM_COST"NT_GBE_BASE"
CDS_LOCATION"R1R1"
CDS_LIB"mstr_discrete"
SEC_TYPE"0402"
SEC"1";
"B"
$PN"2"48;
"A"
$PN"1"51;
%"P3V3_STBY"
"1","(-6925,800)","0","mstr_symbols","I199";
;
HDL_POWER"P3V3_STBY"
BODY_TYPE"PLUMBING"
SIZE"1B"
CDS_LIB"mstr_symbols"
VOLTAGE"3.3V";
"G\NAC"16;
%"RES"
"2","(-6925,550)","0","mstr_discrete","I200";
;
CDS_SEC"1"
VALUE"10.0K"
PART_NUMBER"G21796-016"
MATERIAL"CHIP"
WATTAGE"1/16W"
PACK_TYPE"0402"
TOLERANCE"1%"
LOCATION"R9E4"
BOM_COST"NT_GBE_BASE"
SEC_TYPE"0402"
SEC"1"
ROOM"NIC_SPRV"
CDS_LOCATION"R9E4"
CDS_LIB"mstr_discrete";
"A"
$PN"1"16;
"B"
$PN"2"48;
%"RES"
"1","(-6800,1575)","0","mstr_discrete","I201";
;
CDS_SEC"1"
LOCATION"R9E18"
TOLERANCE"5%"
WATTAGE"1/16W"
PACK_TYPE"0402"
MATERIAL"CHIP"
GROUP"NI_I210&RJ45"
PART_NUMBER"G21497-005"
VALUE"0.0"
BOM_COST"NT_GBE_BASE"
CDS_LOCATION"R9E18"
ROOM"NIC_SPRV"
SEC_TYPE"0402"
SEC"1"
CDS_LIB"mstr_discrete";
"B"
$PN"2"54;
"A"
$PN"1"87;
%"GND"
"1","(-1900,1375)","0","mstr_symbols","I204";
;
CDS_LIB"mstr_symbols"
SIZE"1B"
VOLTAGE"0.0V"
BODY_TYPE"PLUMBING"
HDL_POWER"GND";
"A\NAC"17;
%"GND"
"1","(-3050,1225)","0","mstr_symbols","I207";
;
VOLTAGE"0.0V"
CDS_LIB"mstr_symbols"
SIZE"1B"
BODY_TYPE"PLUMBING"
HDL_POWER"GND";
"A\NAC"18;
%"GND"
"1","(-1300,1350)","0","mstr_symbols","I211";
;
VOLTAGE"0.0V"
SIZE"1B"
CDS_LIB"mstr_symbols"
BODY_TYPE"PLUMBING"
HDL_POWER"GND";
"A\NAC"19;
%"RES"
"2","(-1900,1650)","0","mstr_discrete","I212";
;
TOLERANCE"1%"
MATERIAL"CHIP"
PACK_TYPE"0402"
PART_NUMBER"G21796-016"
WATTAGE"1/16W"
LOCATION"R9E13"
VALUE"10.0K"
CDS_LIB"mstr_discrete"
CDS_LOCATION"R9E13"
ROOM"NIC_SPRV"
BOM_COST"NT_GBE_BASE"
CDS_SEC"1"
$SEC"1";
"A"
$PN"1"32;
"B"
$PN"2"17;
%"RES"
"2","(-3050,1500)","0","mstr_discrete","I213";
;
GROUP"NI_I210&RJ45"
PACK_TYPE"0402"
PART_NUMBER"G21796-016"
MATERIAL"CHIP"
TOLERANCE"1%"
WATTAGE"1/16W"
LOCATION"R1R12"
VALUE"10.0K"
CDS_LIB"mstr_discrete"
BOM_COST"NT_GBE_BASE"
CDS_SEC"1"
$SEC"1"
CDS_LOCATION"R1R12"
ROOM"NIC_SPRV";
"A"
$PN"1"53;
"B"
$PN"2"18;
%"RES"
"2","(-1300,1550)","0","mstr_discrete","I214";
;
MATERIAL"CHIP"
WATTAGE"1/16W"
PACK_TYPE"0402"
VALUE"10.0K"
TOLERANCE"1%"
LOCATION"R1T1"
PART_NUMBER"G21796-016"
BOM_COST"NT_GBE_BASE"
CDS_SEC"1"
$SEC"1"
CDS_LOCATION"R1T1"
ROOM"NIC_SPRV"
CDS_LIB"mstr_discrete";
"A"
$PN"1"34;
"B"
$PN"2"19;
%"RES"
"1","(-2400,2675)","0","mstr_discrete","I225";
;
WATTAGE"1/16W"
VALUE"22.1"
TOLERANCE"1.0%"
LOCATION"R9F1"
PART_NUMBER"G21796-250"
MATERIAL"CHIP"
PACK_TYPE"0402"
GROUP"NI_I210&RJ45"
CDS_LOCATION"R9F1"
CDS_LIB"mstr_discrete"
$SEC"1"
CDS_SEC"1";
"B"
$PN"2"85;
"A"
$PN"1"58;
%"RES"
"1","(-2275,2525)","0","mstr_discrete","I228";
;
CDS_SEC"1"
WATTAGE"1/16W"
TOLERANCE"1.0%"
VALUE"22.1"
LOCATION"R9E19"
MATERIAL"CHIP"
PART_NUMBER"G21796-250"
GROUP"NI_I210&RJ45"
PACK_TYPE"0402"
CDS_LOCATION"R9E19"
CDS_LIB"mstr_discrete"
SEC_TYPE"0402"
SEC"1"
ROOM"BMC"
BOM_COST"SM_CONTROLLER";
"B"
$PN"2"83;
"A"
$PN"1"45;
%"RES"
"1","(-1900,2450)","0","mstr_discrete","I229";
;
CDS_SEC"1"
LOCATION"R9E17"
PACK_TYPE"0402"
VALUE"22.1"
MATERIAL"CHIP"
TOLERANCE"1.0%"
WATTAGE"1/16W"
GROUP"NI_I210&RJ45"
PART_NUMBER"G21796-250"
CDS_LOCATION"R9E17"
CDS_LIB"mstr_discrete"
SEC"1"
SEC_TYPE"0402"
ROOM"BMC"
BOM_COST"SM_CONTROLLER";
"B"
$PN"2"26;
"A"
$PN"1"82;
%"RES"
"1","(-2075,2725)","0","mstr_discrete","I235";
;
CDS_SEC"1"
GROUP"NI_I210&RJ45"
WATTAGE"1/16W"
VALUE"33.2"
LOCATION"R9E16"
MATERIAL"CHIP"
PACK_TYPE"0402"
TOLERANCE"1%"
PART_NUMBER"G21796-074"
CDS_LIB"mstr_discrete"
SEC"1"
SEC_TYPE"0402"
CDS_LOCATION"R9E16"
ROOM"SB";
"B"
$PN"2"47;
"A"
$PN"1"44;
%"RES"
"1","(-5600,4025)","0","mstr_discrete","I237";
;
CDS_SEC"1"
PART_NUMBER"G22178-002"
WATTAGE"1/10W"
MATERIAL"CHIP"
TOLERANCE"5.0%"
VALUE"0"
LOCATION"R1R15"
PACK_TYPE"0603"
GROUP"NI_I210&RJ45"
CDS_LIB"mstr_discrete"
CDS_LOCATION"R1R15"
SEC"1"
SEC_TYPE"0603"
ROOM"NIC_SPRV"
BOM_COST"NT_GBE_BASE";
"B"
$PN"2"80;
"A"
$PN"1"22;
%"RES"
"1","(-5800,3875)","0","mstr_discrete","I238";
;
CDS_SEC"1"
GROUP"NI_I210&RJ45"
MATERIAL"CHIP"
PACK_TYPE"0603"
WATTAGE"1/10W"
LOCATION"R1T32"
PART_NUMBER"G22178-002"
VALUE"0"
TOLERANCE"5.0%"
CDS_LIB"mstr_discrete"
CDS_LOCATION"R1T32"
ROOM"NIC_SPRV"
SEC"1"
SEC_TYPE"0603"
BOM_COST"NT_GBE_BASE";
"B"
$PN"2"81;
"A"
$PN"1"23;
%"RES"
"1","(-5600,3525)","0","mstr_discrete","I239";
;
CDS_SEC"1"
TOLERANCE"5.0%"
PART_NUMBER"G22178-002"
LOCATION"R1T34"
VALUE"0"
WATTAGE"1/10W"
MATERIAL"CHIP"
PACK_TYPE"0603"
GROUP"NI_I210&RJ45"
SEC"1"
SEC_TYPE"0603"
CDS_LIB"mstr_discrete"
CDS_LOCATION"R1T34"
ROOM"NIC_SPRV"
BOM_COST"NT_GBE_BASE";
"B"
$PN"2"95;
"A"
$PN"1"12;
%"RES"
"1","(-5800,3725)","0","mstr_discrete","I240";
;
CDS_SEC"1"
LOCATION"R1T33"
PACK_TYPE"0603"
MATERIAL"EMPTY"
TOLERANCE"5.0%"
GROUP"NI_I210&RJ45"
PART_NUMBER"G22178-002"
WATTAGE"1/10W"
VALUE"0"
BOM_COST"NT_GBE_BASE"
ROOM"NIC_SPRV"
SEC_TYPE"0603"
SEC"1"
CDS_LOCATION"R1T33"
CDS_LIB"mstr_discrete";
"B"
$PN"2"95;
"A"
$PN"1"23;
%"CAP_A"
"1","(-1925,875)","0","dev_discrete","I241";
;
CDS_SEC"1"
CDS_LOCATION"C9E12"
GROUP"NI_I210&RJ45"
LOCATION"C9E12"
MATERIAL"EMPTY"
TOLERANCE"20%"
PART_NUMBER"E15431-004"
PACK_TYPE"0603V"
VALUE"22.0UF"
VOLTAGE"4V"
CDS_LIB"dev_discrete"
BOM_COST"NT_GBE_BASE"
SEC"1"
SEC_TYPE"0603V"
ROOM"NIC_SPRV";
"B"
$PN"2"8;
"A"
$PN"1"7;
%"GND"
"1","(-6100,525)","0","mstr_symbols","I243";
;
CDS_LIB"mstr_symbols"
BOM_COST"PVPP_KLM_VR"
ROOM"PVPP_KLM_VR"
BODY_TYPE"PLUMBING"
VOLTAGE"0"
SIZE"1B"
HDL_POWER"GND";
"A\NAC"20;
%"SC22U16V5MX-4-GP"
"1","(-5800,825)","0","w_hdl","I244";
;
CDS_SEC"1"
CDS_LOCATION"C22W34"
TOLERANCE"20%"
TYPE"X6S"
RATED"16V"
ATTRIBUTE"22UF"
LOCATION"C22W34"
VALUE"SC22U16V5MX-4-GP"
POP"NOPOP"
PACK_SIZE"0805"
GROUP"NI_I210&RJ45"
PACK_TYPE"SMD-BCG5"
SEC"1"
SEC_TYPE"SMD-BCG5"
PART_NUMBER"078.22611.0811"
CDS_LIB"w_hdl"
CDS_LMAN_SYM_OUTLINE"-50,25,50,-25";
"2"
$PN"2"20;
"1"
$PN"1"14;
%"SC22U16V5MX-4-GP"
"1","(-6100,825)","0","w_hdl","I245";
;
CDS_SEC"1"
CDS_LOCATION"C9F2"
LOCATION"C9F2"
POP"NOPOP"
RATED"16V"
PACK_SIZE"0805"
TYPE"X6S"
TOLERANCE"20%"
VALUE"SC22U16V5MX-4-GP"
ATTRIBUTE"22UF"
GROUP"NI_I210&RJ45"
CDS_LMAN_SYM_OUTLINE"-50,25,50,-25"
CDS_LIB"w_hdl"
PART_NUMBER"078.22611.0811"
SEC_TYPE"SMD-BCG5"
SEC"1"
PACK_TYPE"SMD-BCG5";
"2"
$PN"2"20;
"1"
$PN"1"14;
%"SC22U16V5MX-4-GP"
"1","(-3700,800)","0","w_hdl","I246";
;
CDS_SEC"1"
CDS_LOCATION"C22W35"
PACK_SIZE"0805"
LOCATION"C22W35"
RATED"16V"
TOLERANCE"20%"
ATTRIBUTE"22UF"
TYPE"X6S"
POP"NOPOP"
VALUE"SC22U16V5MX-4-GP"
GROUP"NI_I210&RJ45"
CDS_LMAN_SYM_OUTLINE"-50,25,50,-25"
CDS_LIB"w_hdl"
PART_NUMBER"078.22611.0811"
SEC_TYPE"SMD-BCG5"
SEC"1"
PACK_TYPE"SMD-BCG5";
"2"
$PN"2"21;
"1"
$PN"1"6;
%"GND"
"1","(-4000,525)","0","mstr_symbols","I247";
;
HDL_POWER"GND"
SIZE"1B"
VOLTAGE"0"
BODY_TYPE"PLUMBING"
ROOM"PVPP_KLM_VR"
BOM_COST"PVPP_KLM_VR"
CDS_LIB"mstr_symbols";
"A\NAC"21;
%"SC22U16V5MX-4-GP"
"1","(-4000,800)","0","w_hdl","I248";
;
CDS_SEC"1"
CDS_LOCATION"C9E6"
PACK_SIZE"0805"
TOLERANCE"20%"
VALUE"SC22U16V5MX-4-GP"
ATTRIBUTE"22UF"
LOCATION"C9E6"
TYPE"X6S"
POP"NOPOP"
RATED"16V"
GROUP"NI_I210&RJ45"
CDS_LMAN_SYM_OUTLINE"-50,25,50,-25"
CDS_LIB"w_hdl"
PART_NUMBER"078.22611.0811"
SEC_TYPE"SMD-BCG5"
SEC"1"
PACK_TYPE"SMD-BCG5";
"2"
$PN"2"21;
"1"
$PN"1"6;
%"CAP"
"1","(-7750,1200)","0","mstr_discrete","I249";
;
CDS_SEC"1"
LOCATION"C9E9"
VALUE"15.0PF"
PART_NUMBER"A36095-047"
TOLERANCE"5%"
VOLTAGE"50V"
PACK_TYPE"0402LF"
MATERIAL"COG"
GROUP"NI_I210&RJ45"
BOM_COST"SYS_CLOCK"
ROOM"SB"
CDS_LIB"mstr_discrete"
SEC"1"
SEC_TYPE"0402LF"
CDS_LOCATION"C9E9";
"A"
$PN"1"39;
"B"
$PN"2"2;
%"CAP"
"1","(-7325,1200)","0","mstr_discrete","I250";
;
CDS_SEC"1"
PACK_TYPE"0402LF"
PART_NUMBER"A36095-047"
VALUE"15.0PF"
VOLTAGE"50V"
LOCATION"C9E8"
MATERIAL"COG"
TOLERANCE"5%"
GROUP"NI_I210&RJ45"
SEC_TYPE"0402LF"
SEC"1"
CDS_LIB"mstr_discrete"
ROOM"SB"
BOM_COST"SYS_CLOCK"
CDS_LOCATION"C9E8";
"A"
$PN"1"87;
"B"
$PN"2"1;
%"RES"
"2","(-6950,3275)","0","mstr_discrete","I252";
;
CDS_SEC"1"
LOCATION"R9W36"
VALUE"10.0K"
TOLERANCE"1%"
PACK_TYPE"0402"
MATERIAL"CHIP"
WATTAGE"1/16W"
GROUP"NI_I210&RJ45"
PART_NUMBER"G21796-016"
BOM_COST"NT_GBE_BASE"
SEC_TYPE"0402"
SEC"1"
ROOM"NIC_SPRV"
CDS_LIB"mstr_discrete"
CDS_LOCATION"R9W36";
"A"
$PN"1"10;
"B"
$PN"2"40;
%"SPRINGVILLE"
"2","(-4200,3125)","0","mstr_intel","I72";
;
CDS_SEC"1"
PART_NUMBER"G47144-004"
LOCATION"EU9E1"
MATERIAL"IC"
GROUP"NI_I210&RJ45"
CDS_LIB"mstr_intel"
SEC"1"
CDS_LOCATION"EU9E1"
PACK_TYPE"SM1"
SEC_TYPE"SM1"
ROOM"NIC_SPRV"
BOM_COST"NT_GBE_BASE";
"VDD1P5<0>"
$PN"56"81;
"VDD1P5_OUT"
$PN"39"23;
"VDD1P5<1>"
$PN"47"23;
"VDD0P9_OUT"
$PN"38"80;
"VDD0P9<0>"
$PN"59"22;
"VDD0P9<1>"
$PN"32"22;
"VDD0P9<2>"
$PN"11"22;
"VDD0P9<3>"
$PN"42"22;
"XTAL2"
$PN"45"97;
"XTAL1"
$PN"46"96;
"VDD3P3<3>"
$PN"27"12;
"VDD3P3<4>"
$PN"10"12;
"SMB_CLK"
$PN"34"84;
"SDP2"
$PN"62"36;
"SDP0"
$PN"63"38;
"RSET"
$PN"48"75;
"PE_WAKE_N"
$PN"16"90;
"PE_TP"
$PN"21"55;
"PE_TN"
$PN"20"29;
"PE_RST_N"
$PN"17"73;
"PE_RP"
$PN"24"74;
"PE_RN"
$PN"23"72;
"PECLKP"
$PN"26"89;
"PECLKN"
$PN"25"88;
"NVM_SO"
$PN"14"77;
"NVM_SK"
$PN"13"46;
"NVM_SI"
$PN"12"56;
"NVM_CS_N"
$PN"15"27;
"NC_SI_TX_EN"
$PN"7"57;
"NC_SI_TXD1"
$PN"8"78;
"NC_SI_TXD0"
$PN"9"79;
"NC_SI_RXD1"
$PN"5"45;
"NC_SI_RXD0"
$PN"6"82;
"NC_SI_CRS_DV"
$PN"3"58;
"NC_SI_CLK_IN"
$PN"2"59;
"NC_SI_ARB_OUT"
$PN"44"44;
"NC_SI_ARB_IN"
$PN"43"60;
"NC"
$PN"22"0;
"LED2"
$PN"33"61;
"LED1"
$PN"30"91;
"LED0"
$PN"31"62;
"LAN_PWR_GOOD"
$PN"1"98;
"JTAG_TMS"
$PN"18"100;
"JTAG_TDI"
$PN"29"86;
"JTAG_CLK"
$PN"19"99;
"GND"
$PN"65"24;
"DEV_OFF_N"
$PN"28"40;
"CTOP"
$PN"40"63;
"CBOT"
$PN"37"35;
"MDI_PLUS3_SERP"
$PN"50"64;
"MDI_MINUS3_SERN"
$PN"49"65;
"MDI_PLUS2_SETP"
$PN"53"66;
"MDI_MINUS2_SETN"
$PN"52"67;
"MDI_PLUS1_SFP_I2C_CLK"
$PN"55"68;
"MDI_MINUS1_SRDS_SIG_DET"
$PN"54"69;
"MDI_MINUS0_SFP_I2C_DATA"
$PN"57"70;
"MDI_PLUS0_NC"
$PN"58"71;
"SDP3"
$PN"60"25;
"SDP1_PCIE_DIS_SDP1"
$PN"61"37;
"JTAG_TDO"
$PN"4"94;
"SMB_ALRT_N"
$PN"35"93;
"SMB_DATA"
$PN"36"92;
"VDD3P3<0>"
$PN"64"12;
"VDD3P3<1>"
$PN"51"95;
"VDD3P3<2>"
$PN"41"12;
%"P0V9_LAN"
"1","(-5725,4525)","0","mstr_symbols","I73";
;
VOLTAGE"0.9V"
CDS_LIB"mstr_symbols"
BODY_TYPE"PLUMBING"
HDL_POWER"P0V9_LAN";
"G\NAC"22;
%"P1V5_LAN"
"1","(-6375,4300)","0","mstr_symbols","I74";
;
HDL_POWER"P1V5_LAN"
BODY_TYPE"PLUMBING"
CDS_LIB"mstr_symbols"
VOLTAGE"1.5V";
"G\NAC"23;
%"CAP"
"1","(-2725,3500)","0","mstr_discrete","I76";
;
CDS_SEC"1"
GROUP"NI_I210&RJ45"
PART_NUMBER"A36096-063"
VALUE"0.039UF"
PACK_TYPE"0402LF"
TOLERANCE"10%"
LOCATION"C9E7"
MATERIAL"X7R"
VOLTAGE"25V"
CDS_LIB"mstr_discrete"
ROOM"NIC_SPRV"
CDS_LOCATION"C9E7"
SEC"1"
BOM_COST"NT_GBE_BASE"
SEC_TYPE"0402LF";
"A"
$PN"1"63;
"B"
$PN"2"35;
%"GND"
"1","(-3175,1425)","0","mstr_symbols","I77";
;
VOLTAGE"0.0V"
CDS_LIB"mstr_symbols"
SIZE"1B"
BODY_TYPE"PLUMBING"
HDL_POWER"GND";
"A\NAC"24;
%"CAP_A"
"2","(-1650,2075)","0","dev_discrete","I87";
;
MATERIAL"X7R"
PACK_TYPE"0402V"
TOLERANCE"10%"
PART_NUMBER"A36096-030"
VALUE"0.1UF"
LOCATION"C9E5"
GROUP"NI_I210&RJ45"
VOLTAGE"16V"
CDS_LIB"dev_discrete"
ROOM"NIC_SPRV"
BOM_COST"NT_GBE_BASE"
SEC"1"
SEC_TYPE"0402V"
CDS_SEC"1"
CDS_LOCATION"C9E5";
"A"
$PN"1"29;
"B"
$PN"2"33;
%"CAP_A"
"2","(-2400,2125)","0","dev_discrete","I88";
;
VOLTAGE"16V"
PART_NUMBER"A36096-030"
MATERIAL"X7R"
PACK_TYPE"0402V"
LOCATION"C9E4"
TOLERANCE"10%"
VALUE"0.1UF"
GROUP"NI_I210&RJ45"
CDS_LIB"dev_discrete"
ROOM"NIC_SPRV"
BOM_COST"NT_GBE_BASE"
SEC"1"
SEC_TYPE"0402V"
CDS_LOCATION"C9E4"
CDS_SEC"1";
"A"
$PN"1"55;
"B"
$PN"2"30;
%"CAP_A"
"2","(-5925,2125)","0","dev_discrete","I89";
;
VALUE"0.1UF"
TOLERANCE"10%"
PACK_TYPE"0402V"
MATERIAL"X7R"
VOLTAGE"16V"
LOCATION"C2M23"
PART_NUMBER"A36096-030"
GROUP"NI_I210&RJ45"
SEC"1"
SEC_TYPE"0402V"
BOM_COST"NT_GBE_BASE"
ROOM"NIC_SPRV"
CDS_SEC"1"
CDS_LIB"dev_discrete"
CDS_LOCATION"C2M23";
"A"
$PN"1"52;
"B"
$PN"2"74;
%"CAP_A"
"2","(-6150,2075)","0","dev_discrete","I90";
;
LOCATION"C2M24"
PART_NUMBER"A36096-030"
VOLTAGE"16V"
MATERIAL"X7R"
PACK_TYPE"0402V"
VALUE"0.1UF"
TOLERANCE"10%"
GROUP"NI_I210&RJ45"
SEC_TYPE"0402V"
SEC"1"
BOM_COST"NT_GBE_BASE"
CDS_SEC"1"
CDS_LIB"dev_discrete"
CDS_LOCATION"C2M24"
ROOM"NIC_SPRV";
"A"
$PN"1"50;
"B"
$PN"2"72;
END.
